(kicad_pcb
	(version 20260206)
	(generator "pcbnew")
	(generator_version "10.0")
	(general
		(thickness 1.6)
		(legacy_teardrops no)
	)
	(paper "A4")
	(title_block
		(title "03242023_DA0F0TMBIJ0_F0T_Motherboard_J_brd_V01_OCP.brd")
		(comment 1 "Grand Teton / footprints 1827-1832 of 6105")
	)
	(layers
		(0 "F.Cu" signal "TOP")
		(4 "In1.Cu" signal "GND")
		(6 "In2.Cu" signal "IN1")
		(8 "In3.Cu" signal "GND1")
		(10 "In4.Cu" signal "IN2")
		(12 "In5.Cu" signal "GND2")
		(14 "In6.Cu" signal "IN3")
		(16 "In7.Cu" signal "GND3")
		(18 "In8.Cu" signal "VCC")
		(20 "In9.Cu" signal "VCC1")
		(22 "In10.Cu" signal "GND4")
		(24 "In11.Cu" signal "IN4")
		(26 "In12.Cu" signal "GND5")
		(28 "In13.Cu" signal "IN5")
		(30 "In14.Cu" signal "GND6")
		(32 "In15.Cu" signal "IN6")
		(34 "In16.Cu" signal "GND7")
		(2 "B.Cu" signal "BOTTOM")
		(9 "F.Adhes" user "F.Adhesive")
		(11 "B.Adhes" user "B.Adhesive")
		(13 "F.Paste" user "Package Geometry/Pastemask Top")
		(15 "B.Paste" user "Package Geometry/Pastemask Bottom")
		(5 "F.SilkS" user "Ref Des/Silkscreen Top")
		(7 "B.SilkS" user "Ref Des/Silkscreen Bottom")
		(1 "F.Mask" user "Board Geometry/Soldermask Top")
		(3 "B.Mask" user "Board Geometry/Soldermask Bottom")
		(17 "Dwgs.User" user "User.Drawings")
		(19 "Cmts.User" user "User.Comments")
		(21 "Eco1.User" user "User.Eco1")
		(23 "Eco2.User" user "User.Eco2")
		(25 "Edge.Cuts" user "Board Geometry/Outline")
		(27 "Margin" user)
		(31 "F.CrtYd" user "Package Geometry/Place Bound Top")
		(29 "B.CrtYd" user "Package Geometry/Place Bound Bottom")
		(35 "F.Fab" user "Ref Des/Assembly Top")
		(33 "B.Fab" user "Ref Des/Assembly Bottom")
	)
	(footprint ""
		(layer "F.Cu")
		(at 194.371468 -76.016866)
		(property "Reference" "R1291"
			(at 0 0 0)
			(layer "F.SilkS")
			(hide yes)
			(effects
				(font
					(size 1.27 1.27)
				)
			)
		)
		(property "Value" ""
			(at 0 0 0)
			(layer "F.Fab")
			(effects
				(font
					(size 1.27 1.27)
				)
			)
		)
		(duplicate_pad_numbers_are_jumpers no)
		(fp_line
			(start -0.7874 -0.4064)
			(end 0.7874 -0.4064)
			(stroke
				(width 0.1524)
				(type default)
			)
			(layer "F.SilkS")
		)
		(fp_line
			(start -0.7874 0.4064)
			(end -0.7874 -0.4064)
			(stroke
				(width 0.1524)
				(type default)
			)
			(layer "F.SilkS")
		)
		(fp_line
			(start 0.7874 -0.4064)
			(end 0.7874 0.4064)
			(stroke
				(width 0.1524)
				(type default)
			)
			(layer "F.SilkS")
		)
		(fp_line
			(start 0.7874 0.4064)
			(end -0.7874 0.4064)
			(stroke
				(width 0.1524)
				(type default)
			)
			(layer "F.SilkS")
		)
		(fp_line
			(start -0.67945 -0.305054)
			(end -0.12065 -0.305054)
			(stroke
				(width 0.1)
				(type default)
			)
			(layer "F.Fab")
		)
		(fp_line
			(start -0.67945 0.3048)
			(end -0.67945 -0.305054)
			(stroke
				(width 0.1)
				(type default)
			)
			(layer "F.Fab")
		)
		(fp_line
			(start -0.12065 -0.305054)
			(end -0.12065 -0.2794)
			(stroke
				(width 0.1)
				(type default)
			)
			(layer "F.Fab")
		)
		(fp_line
			(start -0.12065 -0.2794)
			(end 0.12065 -0.2794)
			(stroke
				(width 0.1)
				(type default)
			)
			(layer "F.Fab")
		)
		(fp_line
			(start -0.12065 0.2794)
			(end -0.12065 0.3048)
			(stroke
				(width 0.1)
				(type default)
			)
			(layer "F.Fab")
		)
		(fp_line
			(start -0.12065 0.3048)
			(end -0.67945 0.3048)
			(stroke
				(width 0.1)
				(type default)
			)
			(layer "F.Fab")
		)
		(fp_line
			(start 0.120396 0.2794)
			(end -0.12065 0.2794)
			(stroke
				(width 0.1)
				(type default)
			)
			(layer "F.Fab")
		)
		(fp_line
			(start 0.120396 0.3048)
			(end 0.120396 0.2794)
			(stroke
				(width 0.1)
				(type default)
			)
			(layer "F.Fab")
		)
		(fp_line
			(start 0.12065 -0.3048)
			(end 0.67945 -0.3048)
			(stroke
				(width 0.1)
				(type default)
			)
			(layer "F.Fab")
		)
		(fp_line
			(start 0.12065 -0.2794)
			(end 0.12065 -0.3048)
			(stroke
				(width 0.1)
				(type default)
			)
			(layer "F.Fab")
		)
		(fp_line
			(start 0.67945 -0.3048)
			(end 0.67945 0.3048)
			(stroke
				(width 0.1)
				(type default)
			)
			(layer "F.Fab")
		)
		(fp_line
			(start 0.67945 0.3048)
			(end 0.120396 0.3048)
			(stroke
				(width 0.1)
				(type default)
			)
			(layer "F.Fab")
		)
		(pad "1" smd circle
			(at -0.40005 0)
			(size 0 0)
			(layers "F.Cu" "F.Mask" "F.Paste")
			(net "NCSI_BMC_CRS_DV_R")
		)
		(pad "2" smd circle
			(at 0.40005 0)
			(size 0 0)
			(layers "F.Cu" "F.Mask" "F.Paste")
			(net "RMII_OCP_BMC_CRSDV")
		)
	)
	(footprint ""
		(layer "F.Cu")
		(at 33.7693 -133.444996 180)
		(property "Reference" "PC468"
			(at 0 0 180)
			(layer "F.SilkS")
			(hide yes)
			(effects
				(font
					(size 1.27 1.27)
				)
			)
		)
		(property "Value" ""
			(at 0 0 180)
			(layer "F.Fab")
			(effects
				(font
					(size 1.27 1.27)
				)
			)
		)
		(duplicate_pad_numbers_are_jumpers no)
		(fp_line
			(start 0.7874 0.4064)
			(end -0.7874 0.4064)
			(stroke
				(width 0.1524)
				(type default)
			)
			(layer "F.SilkS")
		)
		(fp_line
			(start 0.7874 -0.4064)
			(end 0.7874 0.4064)
			(stroke
				(width 0.1524)
				(type default)
			)
			(layer "F.SilkS")
		)
		(fp_line
			(start -0.7874 0.4064)
			(end -0.7874 -0.4064)
			(stroke
				(width 0.1524)
				(type default)
			)
			(layer "F.SilkS")
		)
		(fp_line
			(start -0.7874 -0.4064)
			(end 0.7874 -0.4064)
			(stroke
				(width 0.1524)
				(type default)
			)
			(layer "F.SilkS")
		)
		(fp_line
			(start 0.67945 0.3048)
			(end 0.120396 0.3048)
			(stroke
				(width 0.1)
				(type default)
			)
			(layer "F.Fab")
		)
		(fp_line
			(start 0.67945 -0.3048)
			(end 0.67945 0.3048)
			(stroke
				(width 0.1)
				(type default)
			)
			(layer "F.Fab")
		)
		(fp_line
			(start 0.12065 -0.2794)
			(end 0.12065 -0.3048)
			(stroke
				(width 0.1)
				(type default)
			)
			(layer "F.Fab")
		)
		(fp_line
			(start 0.12065 -0.3048)
			(end 0.67945 -0.3048)
			(stroke
				(width 0.1)
				(type default)
			)
			(layer "F.Fab")
		)
		(fp_line
			(start 0.120396 0.3048)
			(end 0.120396 0.2794)
			(stroke
				(width 0.1)
				(type default)
			)
			(layer "F.Fab")
		)
		(fp_line
			(start 0.120396 0.2794)
			(end -0.12065 0.2794)
			(stroke
				(width 0.1)
				(type default)
			)
			(layer "F.Fab")
		)
		(fp_line
			(start -0.12065 0.3048)
			(end -0.67945 0.3048)
			(stroke
				(width 0.1)
				(type default)
			)
			(layer "F.Fab")
		)
		(fp_line
			(start -0.12065 0.2794)
			(end -0.12065 0.3048)
			(stroke
				(width 0.1)
				(type default)
			)
			(layer "F.Fab")
		)
		(fp_line
			(start -0.12065 -0.2794)
			(end 0.12065 -0.2794)
			(stroke
				(width 0.1)
				(type default)
			)
			(layer "F.Fab")
		)
		(fp_line
			(start -0.12065 -0.305054)
			(end -0.12065 -0.2794)
			(stroke
				(width 0.1)
				(type default)
			)
			(layer "F.Fab")
		)
		(fp_line
			(start -0.67945 0.3048)
			(end -0.67945 -0.305054)
			(stroke
				(width 0.1)
				(type default)
			)
			(layer "F.Fab")
		)
		(fp_line
			(start -0.67945 -0.305054)
			(end -0.12065 -0.305054)
			(stroke
				(width 0.1)
				(type default)
			)
			(layer "F.Fab")
		)
		(pad "1" smd circle
			(at -0.40005 0 180)
			(size 0 0)
			(layers "F.Cu" "F.Mask" "F.Paste")
			(net "SH_PVCCINFAON_CPU1_R")
		)
		(pad "2" smd circle
			(at 0.40005 0 180)
			(size 0 0)
			(layers "F.Cu" "F.Mask" "F.Paste")
			(net "VSENSE_PVCCINFAON_CPU1_DN")
		)
	)
	(footprint ""
		(layer "F.Cu")
		(at 195.06184 -92.832428 90)
		(property "Reference" "R4609"
			(at 0 0 90)
			(layer "F.SilkS")
			(hide yes)
			(effects
				(font
					(size 1.27 1.27)
				)
			)
		)
		(property "Value" ""
			(at 0 0 90)
			(layer "F.Fab")
			(effects
				(font
					(size 1.27 1.27)
				)
			)
		)
		(duplicate_pad_numbers_are_jumpers no)
		(fp_line
			(start 0.7874 -0.4064)
			(end 0.7874 0.4064)
			(stroke
				(width 0.1524)
				(type default)
			)
			(layer "F.SilkS")
		)
		(fp_line
			(start -0.7874 -0.4064)
			(end 0.7874 -0.4064)
			(stroke
				(width 0.1524)
				(type default)
			)
			(layer "F.SilkS")
		)
		(fp_line
			(start 0.7874 0.4064)
			(end -0.7874 0.4064)
			(stroke
				(width 0.1524)
				(type default)
			)
			(layer "F.SilkS")
		)
		(fp_line
			(start -0.7874 0.4064)
			(end -0.7874 -0.4064)
			(stroke
				(width 0.1524)
				(type default)
			)
			(layer "F.SilkS")
		)
		(fp_line
			(start -0.12065 -0.305054)
			(end -0.12065 -0.2794)
			(stroke
				(width 0.1)
				(type default)
			)
			(layer "F.Fab")
		)
		(fp_line
			(start -0.67945 -0.305054)
			(end -0.12065 -0.305054)
			(stroke
				(width 0.1)
				(type default)
			)
			(layer "F.Fab")
		)
		(fp_line
			(start 0.67945 -0.3048)
			(end 0.67945 0.3048)
			(stroke
				(width 0.1)
				(type default)
			)
			(layer "F.Fab")
		)
		(fp_line
			(start 0.12065 -0.3048)
			(end 0.67945 -0.3048)
			(stroke
				(width 0.1)
				(type default)
			)
			(layer "F.Fab")
		)
		(fp_line
			(start 0.12065 -0.2794)
			(end 0.12065 -0.3048)
			(stroke
				(width 0.1)
				(type default)
			)
			(layer "F.Fab")
		)
		(fp_line
			(start -0.12065 -0.2794)
			(end 0.12065 -0.2794)
			(stroke
				(width 0.1)
				(type default)
			)
			(layer "F.Fab")
		)
		(fp_line
			(start 0.120396 0.2794)
			(end -0.12065 0.2794)
			(stroke
				(width 0.1)
				(type default)
			)
			(layer "F.Fab")
		)
		(fp_line
			(start -0.12065 0.2794)
			(end -0.12065 0.3048)
			(stroke
				(width 0.1)
				(type default)
			)
			(layer "F.Fab")
		)
		(fp_line
			(start 0.67945 0.3048)
			(end 0.120396 0.3048)
			(stroke
				(width 0.1)
				(type default)
			)
			(layer "F.Fab")
		)
		(fp_line
			(start 0.120396 0.3048)
			(end 0.120396 0.2794)
			(stroke
				(width 0.1)
				(type default)
			)
			(layer "F.Fab")
		)
		(fp_line
			(start -0.12065 0.3048)
			(end -0.67945 0.3048)
			(stroke
				(width 0.1)
				(type default)
			)
			(layer "F.Fab")
		)
		(fp_line
			(start -0.67945 0.3048)
			(end -0.67945 -0.305054)
			(stroke
				(width 0.1)
				(type default)
			)
			(layer "F.Fab")
		)
		(pad "1" smd circle
			(at -0.40005 0 90)
			(size 0 0)
			(layers "F.Cu" "F.Mask" "F.Paste")
			(net "FM_JTAG_TCK_MUX_SEL_R")
		)
		(pad "2" smd circle
			(at 0.40005 0 90)
			(size 0 0)
			(layers "F.Cu" "F.Mask" "F.Paste")
			(net "FM_JTAG_TCK_MUX_SEL")
		)
	)
	(footprint ""
		(layer "F.Cu")
		(at 190.80988 -133.695948 90)
		(property "Reference" "R1308"
			(at 0 0 90)
			(layer "F.SilkS")
			(hide yes)
			(effects
				(font
					(size 1.27 1.27)
				)
			)
		)
		(property "Value" ""
			(at 0 0 90)
			(layer "F.Fab")
			(effects
				(font
					(size 1.27 1.27)
				)
			)
		)
		(duplicate_pad_numbers_are_jumpers no)
		(fp_line
			(start 0.7874 -0.4064)
			(end 0.7874 0.4064)
			(stroke
				(width 0.1524)
				(type default)
			)
			(layer "F.SilkS")
		)
		(fp_line
			(start -0.7874 -0.4064)
			(end 0.7874 -0.4064)
			(stroke
				(width 0.1524)
				(type default)
			)
			(layer "F.SilkS")
		)
		(fp_line
			(start 0.7874 0.4064)
			(end -0.7874 0.4064)
			(stroke
				(width 0.1524)
				(type default)
			)
			(layer "F.SilkS")
		)
		(fp_line
			(start -0.7874 0.4064)
			(end -0.7874 -0.4064)
			(stroke
				(width 0.1524)
				(type default)
			)
			(layer "F.SilkS")
		)
		(fp_line
			(start -0.12065 -0.305054)
			(end -0.12065 -0.2794)
			(stroke
				(width 0.1)
				(type default)
			)
			(layer "F.Fab")
		)
		(fp_line
			(start -0.67945 -0.305054)
			(end -0.12065 -0.305054)
			(stroke
				(width 0.1)
				(type default)
			)
			(layer "F.Fab")
		)
		(fp_line
			(start 0.67945 -0.3048)
			(end 0.67945 0.3048)
			(stroke
				(width 0.1)
				(type default)
			)
			(layer "F.Fab")
		)
		(fp_line
			(start 0.12065 -0.3048)
			(end 0.67945 -0.3048)
			(stroke
				(width 0.1)
				(type default)
			)
			(layer "F.Fab")
		)
		(fp_line
			(start 0.12065 -0.2794)
			(end 0.12065 -0.3048)
			(stroke
				(width 0.1)
				(type default)
			)
			(layer "F.Fab")
		)
		(fp_line
			(start -0.12065 -0.2794)
			(end 0.12065 -0.2794)
			(stroke
				(width 0.1)
				(type default)
			)
			(layer "F.Fab")
		)
		(fp_line
			(start 0.120396 0.2794)
			(end -0.12065 0.2794)
			(stroke
				(width 0.1)
				(type default)
			)
			(layer "F.Fab")
		)
		(fp_line
			(start -0.12065 0.2794)
			(end -0.12065 0.3048)
			(stroke
				(width 0.1)
				(type default)
			)
			(layer "F.Fab")
		)
		(fp_line
			(start 0.67945 0.3048)
			(end 0.120396 0.3048)
			(stroke
				(width 0.1)
				(type default)
			)
			(layer "F.Fab")
		)
		(fp_line
			(start 0.120396 0.3048)
			(end 0.120396 0.2794)
			(stroke
				(width 0.1)
				(type default)
			)
			(layer "F.Fab")
		)
		(fp_line
			(start -0.12065 0.3048)
			(end -0.67945 0.3048)
			(stroke
				(width 0.1)
				(type default)
			)
			(layer "F.Fab")
		)
		(fp_line
			(start -0.67945 0.3048)
			(end -0.67945 -0.305054)
			(stroke
				(width 0.1)
				(type default)
			)
			(layer "F.Fab")
		)
		(pad "1" smd circle
			(at -0.40005 0 90)
			(size 0 0)
			(layers "F.Cu" "F.Mask" "F.Paste")
			(net "FM_RST_PERST_BIT1")
		)
		(pad "2" smd circle
			(at 0.40005 0 90)
			(size 0 0)
			(layers "F.Cu" "F.Mask" "F.Paste")
			(net "GND")
		)
	)
	(footprint ""
		(layer "F.Cu")
		(at 144.54378 -345.129358 180)
		(property "Reference" "PR640"
			(at 0 0 180)
			(layer "F.SilkS")
			(hide yes)
			(effects
				(font
					(size 1.27 1.27)
				)
			)
		)
		(property "Value" ""
			(at 0 0 180)
			(layer "F.Fab")
			(effects
				(font
					(size 1.27 1.27)
				)
			)
		)
		(duplicate_pad_numbers_are_jumpers no)
		(fp_line
			(start 0.7874 0.4064)
			(end -0.7874 0.4064)
			(stroke
				(width 0.1524)
				(type default)
			)
			(layer "F.SilkS")
		)
		(fp_line
			(start 0.7874 -0.4064)
			(end 0.7874 0.4064)
			(stroke
				(width 0.1524)
				(type default)
			)
			(layer "F.SilkS")
		)
		(fp_line
			(start -0.7874 0.4064)
			(end -0.7874 -0.4064)
			(stroke
				(width 0.1524)
				(type default)
			)
			(layer "F.SilkS")
		)
		(fp_line
			(start -0.7874 -0.4064)
			(end 0.7874 -0.4064)
			(stroke
				(width 0.1524)
				(type default)
			)
			(layer "F.SilkS")
		)
		(fp_line
			(start 0.67945 0.3048)
			(end 0.120396 0.3048)
			(stroke
				(width 0.1)
				(type default)
			)
			(layer "F.Fab")
		)
		(fp_line
			(start 0.67945 -0.3048)
			(end 0.67945 0.3048)
			(stroke
				(width 0.1)
				(type default)
			)
			(layer "F.Fab")
		)
		(fp_line
			(start 0.12065 -0.2794)
			(end 0.12065 -0.3048)
			(stroke
				(width 0.1)
				(type default)
			)
			(layer "F.Fab")
		)
		(fp_line
			(start 0.12065 -0.3048)
			(end 0.67945 -0.3048)
			(stroke
				(width 0.1)
				(type default)
			)
			(layer "F.Fab")
		)
		(fp_line
			(start 0.120396 0.3048)
			(end 0.120396 0.2794)
			(stroke
				(width 0.1)
				(type default)
			)
			(layer "F.Fab")
		)
		(fp_line
			(start 0.120396 0.2794)
			(end -0.12065 0.2794)
			(stroke
				(width 0.1)
				(type default)
			)
			(layer "F.Fab")
		)
		(fp_line
			(start -0.12065 0.3048)
			(end -0.67945 0.3048)
			(stroke
				(width 0.1)
				(type default)
			)
			(layer "F.Fab")
		)
		(fp_line
			(start -0.12065 0.2794)
			(end -0.12065 0.3048)
			(stroke
				(width 0.1)
				(type default)
			)
			(layer "F.Fab")
		)
		(fp_line
			(start -0.12065 -0.2794)
			(end 0.12065 -0.2794)
			(stroke
				(width 0.1)
				(type default)
			)
			(layer "F.Fab")
		)
		(fp_line
			(start -0.12065 -0.305054)
			(end -0.12065 -0.2794)
			(stroke
				(width 0.1)
				(type default)
			)
			(layer "F.Fab")
		)
		(fp_line
			(start -0.67945 0.3048)
			(end -0.67945 -0.305054)
			(stroke
				(width 0.1)
				(type default)
			)
			(layer "F.Fab")
		)
		(fp_line
			(start -0.67945 -0.305054)
			(end -0.12065 -0.305054)
			(stroke
				(width 0.1)
				(type default)
			)
			(layer "F.Fab")
		)
		(pad "1" smd circle
			(at -0.40005 0 180)
			(size 0 0)
			(layers "F.Cu" "F.Mask" "F.Paste")
			(net "P3V3")
		)
		(pad "2" smd circle
			(at 0.40005 0 180)
			(size 0 0)
			(layers "F.Cu" "F.Mask" "F.Paste")
			(net "PVCCIN_CPU1_PVCC")
		)
	)
	(footprint ""
		(layer "F.Cu")
		(at 197.41388 -103.685848)
		(property "Reference" "R1844"
			(at 0 0 0)
			(layer "F.SilkS")
			(hide yes)
			(effects
				(font
					(size 1.27 1.27)
				)
			)
		)
		(property "Value" ""
			(at 0 0 0)
			(layer "F.Fab")
			(effects
				(font
					(size 1.27 1.27)
				)
			)
		)
		(duplicate_pad_numbers_are_jumpers no)
		(fp_line
			(start -0.7874 -0.4064)
			(end 0.7874 -0.4064)
			(stroke
				(width 0.1524)
				(type default)
			)
			(layer "F.SilkS")
		)
		(fp_line
			(start -0.7874 0.4064)
			(end -0.7874 -0.4064)
			(stroke
				(width 0.1524)
				(type default)
			)
			(layer "F.SilkS")
		)
		(fp_line
			(start 0.7874 -0.4064)
			(end 0.7874 0.4064)
			(stroke
				(width 0.1524)
				(type default)
			)
			(layer "F.SilkS")
		)
		(fp_line
			(start 0.7874 0.4064)
			(end -0.7874 0.4064)
			(stroke
				(width 0.1524)
				(type default)
			)
			(layer "F.SilkS")
		)
		(fp_line
			(start -0.67945 -0.305054)
			(end -0.12065 -0.305054)
			(stroke
				(width 0.1)
				(type default)
			)
			(layer "F.Fab")
		)
		(fp_line
			(start -0.67945 0.3048)
			(end -0.67945 -0.305054)
			(stroke
				(width 0.1)
				(type default)
			)
			(layer "F.Fab")
		)
		(fp_line
			(start -0.12065 -0.305054)
			(end -0.12065 -0.2794)
			(stroke
				(width 0.1)
				(type default)
			)
			(layer "F.Fab")
		)
		(fp_line
			(start -0.12065 -0.2794)
			(end 0.12065 -0.2794)
			(stroke
				(width 0.1)
				(type default)
			)
			(layer "F.Fab")
		)
		(fp_line
			(start -0.12065 0.2794)
			(end -0.12065 0.3048)
			(stroke
				(width 0.1)
				(type default)
			)
			(layer "F.Fab")
		)
		(fp_line
			(start -0.12065 0.3048)
			(end -0.67945 0.3048)
			(stroke
				(width 0.1)
				(type default)
			)
			(layer "F.Fab")
		)
		(fp_line
			(start 0.120396 0.2794)
			(end -0.12065 0.2794)
			(stroke
				(width 0.1)
				(type default)
			)
			(layer "F.Fab")
		)
		(fp_line
			(start 0.120396 0.3048)
			(end 0.120396 0.2794)
			(stroke
				(width 0.1)
				(type default)
			)
			(layer "F.Fab")
		)
		(fp_line
			(start 0.12065 -0.3048)
			(end 0.67945 -0.3048)
			(stroke
				(width 0.1)
				(type default)
			)
			(layer "F.Fab")
		)
		(fp_line
			(start 0.12065 -0.2794)
			(end 0.12065 -0.3048)
			(stroke
				(width 0.1)
				(type default)
			)
			(layer "F.Fab")
		)
		(fp_line
			(start 0.67945 -0.3048)
			(end 0.67945 0.3048)
			(stroke
				(width 0.1)
				(type default)
			)
			(layer "F.Fab")
		)
		(fp_line
			(start 0.67945 0.3048)
			(end 0.120396 0.3048)
			(stroke
				(width 0.1)
				(type default)
			)
			(layer "F.Fab")
		)
		(pad "1" smd circle
			(at -0.40005 0)
			(size 0 0)
			(layers "F.Cu" "F.Mask" "F.Paste")
			(net "RST_PFR_OVR_SRTC_R")
		)
		(pad "2" smd circle
			(at 0.40005 0)
			(size 0 0)
			(layers "F.Cu" "F.Mask" "F.Paste")
			(net "RST_PFR_OVR_SRTC")
		)
	)
)
